FILE_TYPE = CONNECTIVITY;
{Allegro Design Entry HDL 17.4-2019 S026 (4007227) 1/17/2022}
"PAGE_NUMBER" = 396;
0"NC";
1"P5E_CPU1_P1_TX_C_DN<15:8>";
2"P5E_CPU1_P1_TX_C_DP<15:8>";
3"P5E_CPU1_P1_TX_C_DP<7:0>";
4"P5E_CPU1_P1_TX_C_DN<7:0>";
5"P5E_CPU1_P1_TX_C_DN<15>";
6"P5E_CPU1_P1_TX_C_DP<15>";
7"P5E_CPU1_P1_TX_C_DP<14>";
8"P5E_CPU1_P1_TX_C_DN<14>";
9"P5E_CPU1_P1_TX_C_DP<13>";
10"P5E_CPU1_P1_TX_C_DN<13>";
11"P5E_CPU1_P1_TX_C_DN<4>";
12"P5E_CPU1_P1_TX_C_DP<2>";
13"P5E_CPU1_P1_TX_C_DP<1>";
14"P5E_CPU1_P1_TX_C_DN<1>";
15"P5E_CPU1_P1_TX_C_DN<0>";
16"P5E_CPU1_P1_TX_C_DP<0>";
17"P5E_CPU1_P1_TX_C_DN<7>";
18"P5E_CPU1_P1_TX_C_DN<5>";
19"P5E_CPU1_P1_TX_C_DN<3>";
20"P5E_CPU1_P1_TX_C_DN<2>";
21"P5E_CPU1_P1_TX_C_DN<6>";
22"P5E_CPU1_P1_TX_C_DP<10>";
23"P5E_CPU1_P1_TX_C_DP<9>";
24"P5E_CPU1_P1_TX_C_DP<11>";
25"P5E_CPU1_P1_TX_C_DP<8>";
26"P5E_CPU1_P1_TX_C_DN<8>";
27"P5E_CPU1_P1_TX_C_DN<10>";
28"P5E_CPU1_P1_TX_C_DN<9>";
29"P5E_CPU1_P1_TX_C_DP<7>";
30"P5E_CPU1_P1_TX_C_DP<3>";
31"P5E_CPU1_P1_TX_C_DP<4>";
32"P5E_CPU1_P1_TX_C_DP<5>";
33"P5E_CPU1_P1_TX_C_DP<6>";
34"P5E_CPU1_P1_TX_C_DP<12>";
35"P5E_CPU1_P1_TX_C_DN<11>";
36"P5E_CPU1_P1_TX_C_DN<12>";
%"PT5161LRS"
"8","(-7825,3950)","0","pure_quanta","I1";
;
LOCATION"U6015"
$SEC"8"
CDS_SEC"8"
MATERIAL"IC"
PART_TYPE"SMLF"
VALUE"PT5161LRS"
CDS_LIB"pure_quanta"
CDS_LMAN_SYM_OUTLINE"-350,1450,300,-1400"
NEEDS_NO_SIZE"TRUE"
PART_NUMBER"AJ051610U03";
"B_PERN7"
$PN"CD35"25;
"B_PERP7"
$PN"CB34"26;
"B_PERN6"
$PN"BU35"23;
"B_PERP6"
$PN"BR34"28;
"B_PERN5"
$PN"BK35"22;
"B_PERP5"
$PN"BH34"27;
"B_PERN4"
$PN"BC35"24;
"B_PERP4"
$PN"BA34"35;
"B_PERN3"
$PN"AT35"34;
"B_PERP3"
$PN"AP34"36;
"B_PERN2"
$PN"AJ35"9;
"B_PERP2"
$PN"AG34"10;
"B_PERN1"
$PN"AB35"8;
"B_PERP1"
$PN"Y34"7;
"B_PERN0"
$PN"R35"6;
"B_PERP0"
$PN"N34"5;
%"TAP"
"1","(-6800,4150)","0","standard","I10";
;
CDS_LIB"standard"
BODY_TYPE"PLUMBING"
HDL_TAP"TRUE";
"B \NAC \NWC"1;
"S \NAC"
BN"12"36;
%"TAP"
"1","(-6600,4050)","0","standard","I11";
;
CDS_LIB"standard"
BODY_TYPE"PLUMBING"
HDL_TAP"TRUE";
"B \NAC \NWC"2;
"S \NAC"
BN"12"34;
%"TAP"
"1","(-6600,4400)","0","standard","I12";
;
CDS_LIB"standard"
BODY_TYPE"PLUMBING"
HDL_TAP"TRUE";
"B \NAC \NWC"2;
"S \NAC"
BN"13"9;
%"TAP"
"1","(-6800,4500)","0","standard","I13";
;
CDS_LIB"standard"
BODY_TYPE"PLUMBING"
HDL_TAP"TRUE";
"B \NAC \NWC"1;
"S \NAC"
BN"13"10;
%"TAP"
"1","(-6800,4750)","0","standard","I14";
;
CDS_LIB"standard"
BODY_TYPE"PLUMBING"
HDL_TAP"TRUE";
"B \NAC \NWC"1;
"S \NAC"
BN"14"8;
%"TAP"
"1","(-6600,4850)","0","standard","I15";
;
CDS_LIB"standard"
BODY_TYPE"PLUMBING"
HDL_TAP"TRUE";
"B \NAC \NWC"2;
"S \NAC"
BN"14"7;
%"TAP"
"1","(-6800,5200)","0","standard","I16";
;
CDS_LIB"standard"
BODY_TYPE"PLUMBING"
HDL_TAP"TRUE";
"B \NAC \NWC"1;
"S \NAC"
BN"15"5;
%"TAP"
"1","(-6600,5100)","0","standard","I17";
;
CDS_LIB"standard"
BODY_TYPE"PLUMBING"
HDL_TAP"TRUE";
"B \NAC \NWC"2;
"S \NAC"
BN"15"6;
%"TAP"
"1","(-6800,2750)","0","standard","I2";
;
CDS_LIB"standard"
BODY_TYPE"PLUMBING"
HDL_TAP"TRUE";
"B \NAC \NWC"1;
"S \NAC"
BN"8"26;
%"TAP"
"1","(-2175,2700)","0","standard","I20";
;
CDS_LIB"standard"
BODY_TYPE"PLUMBING"
HDL_TAP"TRUE";
"B \NAC \NWC"4;
"S \NAC"
BN"0"15;
%"TAP"
"1","(-1975,2600)","0","standard","I21";
;
CDS_LIB"standard"
BODY_TYPE"PLUMBING"
HDL_TAP"TRUE";
"B \NAC \NWC"3;
"S \NAC"
BN"0"16;
%"TAP"
"1","(-2175,2950)","0","standard","I22";
;
CDS_LIB"standard"
BODY_TYPE"PLUMBING"
HDL_TAP"TRUE";
"B \NAC \NWC"4;
"S \NAC"
BN"1"14;
%"TAP"
"1","(-2175,3400)","0","standard","I23";
;
CDS_LIB"standard"
BODY_TYPE"PLUMBING"
HDL_TAP"TRUE";
"B \NAC \NWC"4;
"S \NAC"
BN"2"20;
%"TAP"
"1","(-1975,3050)","0","standard","I24";
;
CDS_LIB"standard"
BODY_TYPE"PLUMBING"
HDL_TAP"TRUE";
"B \NAC \NWC"3;
"S \NAC"
BN"1"13;
%"TAP"
"1","(-1975,3300)","0","standard","I25";
;
CDS_LIB"standard"
BODY_TYPE"PLUMBING"
HDL_TAP"TRUE";
"B \NAC \NWC"3;
"S \NAC"
BN"2"12;
%"TAP"
"1","(-2175,3750)","0","standard","I26";
;
CDS_LIB"standard"
BODY_TYPE"PLUMBING"
HDL_TAP"TRUE";
"B \NAC \NWC"4;
"S \NAC"
BN"3"19;
%"TAP"
"1","(-1975,3650)","0","standard","I27";
;
CDS_LIB"standard"
BODY_TYPE"PLUMBING"
HDL_TAP"TRUE";
"B \NAC \NWC"3;
"S \NAC"
BN"3"30;
%"TAP"
"1","(-2175,4100)","0","standard","I28";
;
CDS_LIB"standard"
BODY_TYPE"PLUMBING"
HDL_TAP"TRUE";
"B \NAC \NWC"4;
"S \NAC"
BN"4"11;
%"TAP"
"1","(-2175,4450)","0","standard","I29";
;
CDS_LIB"standard"
BODY_TYPE"PLUMBING"
HDL_TAP"TRUE";
"B \NAC \NWC"4;
"S \NAC"
BN"5"18;
%"TAP"
"1","(-6600,2650)","0","standard","I3";
;
CDS_LIB"standard"
BODY_TYPE"PLUMBING"
HDL_TAP"TRUE";
"B \NAC \NWC"2;
"S \NAC"
BN"8"25;
%"TAP"
"1","(-1975,4000)","0","standard","I30";
;
CDS_LIB"standard"
BODY_TYPE"PLUMBING"
HDL_TAP"TRUE";
"B \NAC \NWC"3;
"S \NAC"
BN"4"31;
%"TAP"
"1","(-1975,4350)","0","standard","I31";
;
CDS_LIB"standard"
BODY_TYPE"PLUMBING"
HDL_TAP"TRUE";
"B \NAC \NWC"3;
"S \NAC"
BN"5"32;
%"TAP"
"1","(-2175,4800)","0","standard","I32";
;
CDS_LIB"standard"
BODY_TYPE"PLUMBING"
HDL_TAP"TRUE";
"B \NAC \NWC"4;
"S \NAC"
BN"6"21;
%"TAP"
"1","(-1975,4700)","0","standard","I33";
;
CDS_LIB"standard"
BODY_TYPE"PLUMBING"
HDL_TAP"TRUE";
"B \NAC \NWC"3;
"S \NAC"
BN"6"33;
%"TAP"
"1","(-2175,5150)","0","standard","I34";
;
CDS_LIB"standard"
BODY_TYPE"PLUMBING"
HDL_TAP"TRUE";
"B \NAC \NWC"4;
"S \NAC"
BN"7"17;
%"TAP"
"1","(-1975,5050)","0","standard","I35";
;
CDS_LIB"standard"
BODY_TYPE"PLUMBING"
HDL_TAP"TRUE";
"B \NAC \NWC"3;
"S \NAC"
BN"7"29;
%"PT5161LRS"
"9","(-3200,3900)","0","pure_quanta","I38";
;
LOCATION"U6015"
$SEC"9"
CDS_SEC"9"
PART_TYPE"SMLF"
VALUE"PT5161LRS"
MATERIAL"IC"
NEEDS_NO_SIZE"TRUE"
CDS_LMAN_SYM_OUTLINE"-350,1450,300,-1400"
CDS_LIB"pure_quanta"
PART_NUMBER"AJ051610U03";
"B_PERN15"
$PN"EY35"16;
"B_PERP15"
$PN"EV34"15;
"B_PERN14"
$PN"EN35"14;
"B_PERP14"
$PN"EL34"13;
"B_PERN13"
$PN"EF35"12;
"B_PERP13"
$PN"ED34"20;
"B_PERN12"
$PN"DW35"30;
"B_PERP12"
$PN"DU34"19;
"B_PERN11"
$PN"DM35"31;
"B_PERP11"
$PN"DK34"11;
"B_PERN10"
$PN"DE35"32;
"B_PERP10"
$PN"DC34"18;
"B_PERN9"
$PN"CV35"33;
"B_PERP9"
$PN"CT34"21;
"B_PERN8"
$PN"CL35"29;
"B_PERP8"
$PN"CJ34"17;
%"TAP"
"1","(-6800,3100)","0","standard","I4";
;
CDS_LIB"standard"
BODY_TYPE"PLUMBING"
HDL_TAP"TRUE";
"B \NAC \NWC"1;
"S \NAC"
BN"9"28;
%"TAP"
"1","(-6600,3000)","0","standard","I5";
;
CDS_LIB"standard"
BODY_TYPE"PLUMBING"
HDL_TAP"TRUE";
"B \NAC \NWC"2;
"S \NAC"
BN"9"23;
%"TAP"
"1","(-6600,3350)","0","standard","I6";
;
CDS_LIB"standard"
BODY_TYPE"PLUMBING"
HDL_TAP"TRUE";
"B \NAC \NWC"2;
"S \NAC"
BN"10"22;
%"TAP"
"1","(-6800,3450)","0","standard","I7";
;
CDS_LIB"standard"
BODY_TYPE"PLUMBING"
HDL_TAP"TRUE";
"B \NAC \NWC"1;
"S \NAC"
BN"10"27;
%"TAP"
"1","(-6800,3800)","0","standard","I8";
;
CDS_LIB"standard"
BODY_TYPE"PLUMBING"
HDL_TAP"TRUE";
"B \NAC \NWC"1;
"S \NAC"
BN"11"35;
%"TAP"
"1","(-6600,3700)","0","standard","I9";
;
CDS_LIB"standard"
BODY_TYPE"PLUMBING"
HDL_TAP"TRUE";
"B \NAC \NWC"2;
"S \NAC"
BN"11"24;
END.
